FILE_TYPE = CONNECTIVITY;
{Allegro Design Entry HDL 16.6-p007 (v16-6-112F) 10/10/2012}
"PAGE_NUMBER" = 35;
0"NC";
1"GND\g";
2"TP_CPU0_UPI2_RSVD_DT21";
3"TP_CPU0_UPI2_RSVD_DM21";
4"TP_CPU0_UPI2_RSVD_DL20";
5"TP_CPU0_UPI2_RSVD_DG20";
6"TP_CPU0_UPI2_RSVD_DH19";
7"TP_CPU0_UPI2_RSVD_DK17";
8"TP_CPU0_UPI2_RSVD_DG18";
9"TP_CPU0_UPI2_RSVD_DD17";
10"TP_CPU0_UPI2_RSVD_DF15";
11"TP_CPU0_UPI2_RSVD_DC16";
12"TP_CPU0_UPI2_RSVD_DA16";
13"TP_CPU0_UPI2_RSVD_DP21";
14"TP_CPU0_UPI2_RSVD_DN20";
15"TP_CPU0_UPI2_RSVD_DK19";
16"TP_CPU0_UPI2_RSVD_DJ20";
17"TP_CPU0_UPI2_RSVD_DJ18";
18"TP_CPU0_UPI2_RSVD_DH17";
19"TP_CPU0_UPI2_RSVD_DF17";
20"TP_CPU0_UPI2_RSVD_DE16";
21"TP_CPU0_UPI2_RSVD_DD15";
22"TP_CPU0_UPI2_RSVD_DB15";
23"TP_CPU0_UPI2_RSVD_CW16";
24"TP_CPU0_UPI2_RSVD_CR14";
25"TP_CPU0_UPI2_RSVD_CK13";
26"TP_CPU0_UPI2_RSVD_CH13";
27"TP_CPU0_UPI2_RSVD_CG12";
28"TP_CPU0_UPI2_RSVD_CD11";
29"TP_CPU0_UPI2_RSVD_CB11";
30"TP_CPU0_UPI2_RSVD_CA12";
31"TP_CPU0_UPI2_RSVD_CW14";
32"TP_CPU0_UPI2_RSVD_CU14";
33"TP_CPU0_UPI2_RSVD_CM13";
34"TP_CPU0_UPI2_RSVD_CJ14";
35"TP_CPU0_UPI2_RSVD_CF13";
36"TP_CPU0_UPI2_RSVD_CH11";
37"TP_CPU0_UPI2_RSVD_CE12";
38"TP_CPU0_UPI2_RSVD_CC10";
39"TP_CPU0_UPI2_RSVD_CC12";
40"TP_CPU0_UPI2_RSVD_CF11";
41"TP_CPU0_UPI2_RSVD_CV13";
%"GND"
"1","(-5975,1400)","0","mstr_symbols","I2";
;
VOLTAGE"0.0V"
CDS_LIB"mstr_symbols"
SIZE"1B"
BODY_TYPE"PLUMBING"
HDL_POWER"GND";
"A\NAC"1;
%"SKX_EXT_B"
"15","(-4225,2625)","0","chpset_lib","I3";
;
CDS_SEC"15"
LOCATION"U5D1"
PART_NUMBER"TBD"
MATERIAL"IC"
PACK_TYPE"BGA1"
CDS_LIB"chpset_lib"
SEC_TYPE"BGA1"
SEC"15"
CDS_LOCATION"U5D1"
ROOM"CPU0";
"UPI2_TX_DP<0>"
$PN"DP21"30;
"UPI2_TX_DP<1>"
$PN"DN20"29;
"UPI2_TX_DP<2>"
$PN"DK19"28;
"UPI2_TX_DP<3>"
$PN"DJ20"40;
"UPI2_TX_DP<4>"
$PN"DJ18"27;
"UPI2_TX_DP<5>"
$PN"DH17"26;
"UPI2_TX_DP<6>"
$PN"DF17"25;
"UPI2_TX_DP<7>"
$PN"DE16"24;
"UPI2_TX_DP<8>"
$PN"DD15"41;
"UPI2_TX_DP<9>"
$PN"DB15"23;
"UPI2_TX_DP<10>"
$PN"CW16"22;
"UPI2_TX_DP<11>"
$PN"CV13"21;
"UPI2_TX_DP<12>"
$PN"CR14"20;
"UPI2_TX_DP<13>"
$PN"CK13"19;
"UPI2_TX_DP<14>"
$PN"CH13"18;
"UPI2_TX_DP<15>"
$PN"CG12"17;
"UPI2_TX_DP<16>"
$PN"CF11"16;
"UPI2_TX_DP<17>"
$PN"CD11"15;
"UPI2_TX_DP<18>"
$PN"CB11"14;
"UPI2_TX_DP<19>"
$PN"CA12"13;
"UPI2_TX_DN<0>"
$PN"DT21"39;
"UPI2_TX_DN<1>"
$PN"DM21"38;
"UPI2_TX_DN<2>"
$PN"DL20"37;
"UPI2_TX_DN<3>"
$PN"DG20"36;
"UPI2_TX_DN<4>"
$PN"DH19"35;
"UPI2_TX_DN<5>"
$PN"DK17"34;
"UPI2_TX_DN<6>"
$PN"DG18"33;
"UPI2_TX_DN<7>"
$PN"DD17"32;
"UPI2_TX_DN<8>"
$PN"DF15"31;
"UPI2_TX_DN<9>"
$PN"DC16"12;
"UPI2_TX_DN<10>"
$PN"DA16"11;
"UPI2_TX_DN<11>"
$PN"CW14"10;
"UPI2_TX_DN<12>"
$PN"CU14"9;
"UPI2_TX_DN<13>"
$PN"CM13"8;
"UPI2_TX_DN<14>"
$PN"CJ14"7;
"UPI2_TX_DN<15>"
$PN"CF13"6;
"UPI2_TX_DN<16>"
$PN"CH11"5;
"UPI2_TX_DN<17>"
$PN"CE12"4;
"UPI2_TX_DN<18>"
$PN"CC10"3;
"UPI2_TX_DN<19>"
$PN"CC12"2;
"UPI2_RX_DP<0>"
$PN"DG22"1;
"UPI2_RX_DP<1>"
$PN"DD21"1;
"UPI2_RX_DP<2>"
$PN"DA22"1;
"UPI2_RX_DP<3>"
$PN"DC20"1;
"UPI2_RX_DP<4>"
$PN"DB19"1;
"UPI2_RX_DP<5>"
$PN"CY19"1;
"UPI2_RX_DP<6>"
$PN"CU20"1;
"UPI2_RX_DP<7>"
$PN"CW18"1;
"UPI2_RX_DP<8>"
$PN"CR20"1;
"UPI2_RX_DP<9>"
$PN"CN18"1;
"UPI2_RX_DP<10>"
$PN"CP19"1;
"UPI2_RX_DP<11>"
$PN"CM21"1;
"UPI2_RX_DP<12>"
$PN"CJ16"1;
"UPI2_RX_DP<13>"
$PN"CK17"1;
"UPI2_RX_DP<14>"
$PN"CG16"1;
"UPI2_RX_DP<15>"
$PN"CF15"1;
"UPI2_RX_DP<16>"
$PN"CC14"1;
"UPI2_RX_DP<17>"
$PN"CD17"1;
"UPI2_RX_DP<18>"
$PN"BY15"1;
"UPI2_RX_DP<19>"
$PN"CA16"1;
"UPI2_RX_DN<0>"
$PN"DF23"1;
"UPI2_RX_DN<1>"
$PN"DE22"1;
"UPI2_RX_DN<2>"
$PN"DC22"1;
"UPI2_RX_DN<3>"
$PN"DB21"1;
"UPI2_RX_DN<4>"
$PN"DD19"1;
"UPI2_RX_DN<5>"
$PN"DA20"1;
"UPI2_RX_DN<6>"
$PN"CW20"1;
"UPI2_RX_DN<7>"
$PN"CV19"1;
"UPI2_RX_DN<8>"
$PN"CT21"1;
"UPI2_RX_DN<9>"
$PN"CR18"1;
"UPI2_RX_DN<10>"
$PN"CN20"1;
"UPI2_RX_DN<11>"
$PN"CP21"1;
"UPI2_RX_DN<12>"
$PN"CL16"1;
"UPI2_RX_DN<13>"
$PN"CJ18"1;
"UPI2_RX_DN<14>"
$PN"CH17"1;
"UPI2_RX_DN<15>"
$PN"CE16"1;
"UPI2_RX_DN<16>"
$PN"CD15"1;
"UPI2_RX_DN<17>"
$PN"CF17"1;
"UPI2_RX_DN<18>"
$PN"CB15"1;
"UPI2_RX_DN<19>"
$PN"BY17"1;
END.
